(kicad_pcb
	(version 20241229)
	(generator "pcbnew")
	(generator_version "9.0")
	(general
		(thickness 1.6642)
		(legacy_teardrops no)
	)
	(paper "A3")
	(title_block
		(title "PolarFire SoM")
		(date "2025-07-22")
		(rev "1.1.4")
		(company "Antmicro Ltd")
		(comment 1 "www.antmicro.com")
		(comment 9 "footprints 31-34 of 470")
	)
	(layers
		(0 "F.Cu" mixed)
		(4 "In1.Cu" power)
		(6 "In2.Cu" signal)
		(8 "In3.Cu" power)
		(10 "In4.Cu" signal)
		(12 "In5.Cu" power)
		(14 "In6.Cu" power)
		(16 "In7.Cu" signal)
		(18 "In8.Cu" power)
		(20 "In9.Cu" signal)
		(22 "In10.Cu" power)
		(24 "In11.Cu" signal)
		(26 "In12.Cu" signal)
		(2 "B.Cu" mixed)
		(9 "F.Adhes" user "F.Adhesive")
		(11 "B.Adhes" user "B.Adhesive")
		(13 "F.Paste" user)
		(15 "B.Paste" user)
		(5 "F.SilkS" user "F.Silkscreen")
		(7 "B.SilkS" user "B.Silkscreen")
		(1 "F.Mask" user)
		(3 "B.Mask" user)
		(17 "Dwgs.User" user "User.Drawings")
		(19 "Cmts.User" user "User.Comments")
		(21 "Eco1.User" user "User.Eco1")
		(23 "Eco2.User" user "User.Eco2")
		(25 "Edge.Cuts" user)
		(27 "Margin" user)
		(31 "F.CrtYd" user "F.Courtyard")
		(29 "B.CrtYd" user "B.Courtyard")
		(35 "F.Fab" user)
		(33 "B.Fab" user)
	)
	(footprint "antmicro-footprints:C_0402_1005Metric"
		(layer "F.Cu")
		(at 179.718763 148.663922 180)
		(descr "Capacitor SMD 0402")
		(tags "capacitor SMD 0402")
		(property "Reference" "C88"
			(at -1.341237 -1.286078 0)
			(layer "F.SilkS")
			(effects
				(font
					(size 0.7 0.7)
					(thickness 0.15)
				)
				(justify right bottom)
			)
		)
		(property "Value" "C_22u_0402"
			(at -1.022927 2.155213 0)
			(layer "F.Fab")
			(hide yes)
			(effects
				(font
					(size 0.7 0.7)
					(thickness 0.15)
				)
				(justify right bottom)
			)
		)
		(property "Datasheet" "https://www.murata.com/products/productdetail?partno=GRM158R60J226ME01%23"
			(at 0 0 180)
			(layer "F.Fab")
			(hide yes)
			(effects
				(font
					(size 1.27 1.27)
					(thickness 0.15)
				)
			)
		)
		(property "Description" "SMD Multilayer Ceramic Capacitor, 22 uF, 4 V, 0402 [1005 Metric], X6S"
			(at 0 0 180)
			(layer "F.Fab")
			(hide yes)
			(effects
				(font
					(size 1.27 1.27)
					(thickness 0.15)
				)
			)
		)
		(property "Author" "Antmicro"
			(at 359.437526 297.327844 0)
			(layer "F.Fab")
			(hide yes)
			(effects
				(font
					(size 1 1)
					(thickness 0.15)
				)
			)
		)
		(property "Dielectric" ""
			(at 359.437526 297.327844 0)
			(layer "F.Fab")
			(hide yes)
			(effects
				(font
					(size 1 1)
					(thickness 0.15)
				)
			)
		)
		(property "License" "Apache-2.0"
			(at 359.437526 297.327844 0)
			(layer "F.Fab")
			(hide yes)
			(effects
				(font
					(size 1 1)
					(thickness 0.15)
				)
			)
		)
		(property "MPN" "GRM158R60J226ME01D"
			(at 359.437526 297.327844 0)
			(layer "F.Fab")
			(hide yes)
			(effects
				(font
					(size 1 1)
					(thickness 0.15)
				)
			)
		)
		(property "Manufacturer" "Murata"
			(at 359.437526 297.327844 0)
			(layer "F.Fab")
			(hide yes)
			(effects
				(font
					(size 1 1)
					(thickness 0.15)
				)
			)
		)
		(property "Public" ""
			(at 359.437526 297.327844 0)
			(layer "F.Fab")
			(hide yes)
			(effects
				(font
					(size 1 1)
					(thickness 0.15)
				)
			)
		)
		(property "Val" "22u"
			(at 359.437526 297.327844 0)
			(layer "F.Fab")
			(hide yes)
			(effects
				(font
					(size 1 1)
					(thickness 0.15)
				)
			)
		)
		(property "Voltage" ""
			(at 359.437526 297.327844 0)
			(layer "F.Fab")
			(hide yes)
			(effects
				(font
					(size 1 1)
					(thickness 0.15)
				)
			)
		)
		(sheetname "/Supply/")
		(sheetfile "supply.kicad_sch")
		(attr smd)
		(fp_rect
			(start -0.925 -0.47)
			(end 0.925 0.47)
			(stroke
				(width 0.05)
				(type default)
			)
			(fill no)
			(layer "F.CrtYd")
		)
		(fp_line
			(start 0.504 0.248)
			(end -0.494 0.248)
			(stroke
				(width 0.15)
				(type solid)
			)
			(layer "F.Fab")
		)
		(fp_line
			(start 0.504 -0.25)
			(end 0.504 0.248)
			(stroke
				(width 0.15)
				(type solid)
			)
			(layer "F.Fab")
		)
		(fp_line
			(start -0.494 0.248)
			(end -0.494 -0.25)
			(stroke
				(width 0.15)
				(type solid)
			)
			(layer "F.Fab")
		)
		(fp_line
			(start -0.494 -0.25)
			(end 0.504 -0.25)
			(stroke
				(width 0.15)
				(type solid)
			)
			(layer "F.Fab")
		)
		(fp_text user "Author: Antmicro"
			(at -0.939 3.399 180)
			(layer "F.Fab")
			(effects
				(font
					(size 0.7 0.7)
					(thickness 0.15)
				)
				(justify left bottom)
			)
		)
		(fp_text user "${REFERENCE}"
			(at -0.939 4.599 180)
			(layer "F.Fab")
			(effects
				(font
					(size 0.7 0.7)
					(thickness 0.15)
				)
				(justify left bottom)
			)
		)
		(fp_text user "License: Apache-2.0"
			(at -0.939 5.799 180)
			(layer "F.Fab")
			(effects
				(font
					(size 0.7 0.7)
					(thickness 0.15)
				)
				(justify left bottom)
			)
		)
		(pad "1" smd roundrect
			(at -0.48 0 180)
			(size 0.59 0.64)
			(layers "F.Cu" "F.Mask" "F.Paste")
			(roundrect_rratio 0.25)
			(net 417 "GND")
			(pintype "passive")
		)
		(pad "2" smd roundrect
			(at 0.48 0 180)
			(size 0.59 0.64)
			(layers "F.Cu" "F.Mask" "F.Paste")
			(roundrect_rratio 0.25)
			(net 90 "+5V")
			(pintype "passive")
		)
	)
	(footprint "antmicro-footprints:Fiducial_1mm_Mask2mm"
		(layer "F.Cu")
		(at 228.7 150.5)
		(descr "Circular Fiducial, 1mm bare copper, 3mm soldermask opening")
		(tags "fiducial")
		(property "Reference" "FD5"
			(at 0 -1.4 0)
			(layer "F.SilkS")
			(hide yes)
			(effects
				(font
					(size 0.7 0.7)
					(thickness 0.15)
				)
				(justify left bottom)
			)
		)
		(property "Value" "Fiducial_1mm_Mask2mm"
			(at 0 2.2 0)
			(layer "F.Fab")
			(hide yes)
			(effects
				(font
					(size 0.7 0.7)
					(thickness 0.15)
				)
				(justify left bottom)
			)
		)
		(property "Description" "Fiducial mask "
			(at 0 0 0)
			(layer "F.Fab")
			(hide yes)
			(effects
				(font
					(size 1.27 1.27)
					(thickness 0.15)
				)
			)
		)
		(property "Author" "Antmicro"
			(at 0 0 0)
			(layer "F.Fab")
			(hide yes)
			(effects
				(font
					(size 1 1)
					(thickness 0.15)
				)
			)
		)
		(property "License" "Apache-2.0"
			(at 0 0 0)
			(layer "F.Fab")
			(hide yes)
			(effects
				(font
					(size 1 1)
					(thickness 0.15)
				)
			)
		)
		(property "exclude_from_bom" ""
			(at 0 0 0)
			(layer "F.Fab")
			(hide yes)
			(effects
				(font
					(size 1 1)
					(thickness 0.15)
				)
			)
		)
		(sheetfile "polarfire-som.kicad_sch")
		(attr board_only exclude_from_pos_files exclude_from_bom)
		(fp_circle
			(center 0 0)
			(end 1.24 0)
			(stroke
				(width 0.05)
				(type solid)
			)
			(fill no)
			(layer "F.CrtYd")
		)
		(fp_circle
			(center 0 0)
			(end 0.999 0)
			(stroke
				(width 0.15)
				(type solid)
			)
			(fill no)
			(layer "F.Fab")
		)
		(fp_text user "${REFERENCE}"
			(at -1.25 4.603 0)
			(layer "F.Fab")
			(effects
				(font
					(size 0.7 0.7)
					(thickness 0.15)
				)
				(justify left bottom)
			)
		)
		(fp_text user "Author: Antmicro"
			(at -1.25 5.803 0)
			(layer "F.Fab")
			(effects
				(font
					(size 0.7 0.7)
					(thickness 0.15)
				)
				(justify left bottom)
			)
		)
		(fp_text user "License: Apache-2.0"
			(at -1.25 7.003 0)
			(layer "F.Fab")
			(effects
				(font
					(size 0.7 0.7)
					(thickness 0.15)
				)
				(justify left bottom)
			)
		)
		(pad "" smd circle
			(at 0 0)
			(size 1 1)
			(layers "F.Cu" "F.Mask")
			(solder_mask_margin 0.5)
			(clearance 0.5)
		)
	)
	(footprint "antmicro-footprints:4x0R_0402_array_EXB28V"
		(layer "F.Cu")
		(at 195.61 144.45 180)
		(property "Reference" "R107"
			(at -1.515 1.95 0)
			(layer "F.SilkS")
			(effects
				(font
					(size 0.7 0.7)
					(thickness 0.15)
				)
				(justify right top)
			)
		)
		(property "Value" "4x0R_0402_array"
			(at 0.6604 2.8194 0)
			(layer "F.Fab")
			(hide yes)
			(effects
				(font
					(size 0.7 0.7)
					(thickness 0.15)
				)
				(justify right top)
			)
		)
		(property "Datasheet" "https://industrial.panasonic.com/cdbs/www-data/pdf/AOC0000/AOC0000C14.pdf"
			(at 0 0 0)
			(layer "F.Fab")
			(hide yes)
			(effects
				(font
					(size 1.27 1.27)
					(thickness 0.15)
				)
			)
		)
		(property "Description" "Zero Ohm Network Resistor, Jumper, 0402 [1005 Metric], Thick Film, Isolated, Convex, 4 Resistors"
			(at 0 0 0)
			(layer "F.Fab")
			(hide yes)
			(effects
				(font
					(size 1.27 1.27)
					(thickness 0.15)
				)
			)
		)
		(property "MPN" "EXB28VR000X"
			(at 0 0 180)
			(unlocked yes)
			(layer "F.Fab")
			(hide yes)
			(effects
				(font
					(size 1 1)
					(thickness 0.15)
				)
			)
		)
		(property "Manufacturer" "Panasonic"
			(at 0 0 180)
			(unlocked yes)
			(layer "F.Fab")
			(hide yes)
			(effects
				(font
					(size 1 1)
					(thickness 0.15)
				)
			)
		)
		(property "Author" "Antmicro"
			(at 0 0 180)
			(unlocked yes)
			(layer "F.Fab")
			(hide yes)
			(effects
				(font
					(size 1 1)
					(thickness 0.15)
				)
			)
		)
		(property "License" "Apache-2.0"
			(at 0 0 180)
			(unlocked yes)
			(layer "F.Fab")
			(hide yes)
			(effects
				(font
					(size 1 1)
					(thickness 0.15)
				)
			)
		)
		(property "Val" "4x0R_0402"
			(at 0 0 180)
			(unlocked yes)
			(layer "F.Fab")
			(hide yes)
			(effects
				(font
					(size 1 1)
					(thickness 0.15)
				)
			)
		)
		(sheetname "/HDMI/")
		(sheetfile "hdmi.kicad_sch")
		(attr smd)
		(fp_line
			(start 1.15 0.15)
			(end 1.15 -0.15)
			(stroke
				(width 0.15)
				(type solid)
			)
			(layer "F.SilkS")
		)
		(fp_line
			(start -1.15 -0.15)
			(end -1.15 0.15)
			(stroke
				(width 0.15)
				(type solid)
			)
			(layer "F.SilkS")
		)
		(fp_circle
			(center -0.9652 0.9144)
			(end -0.9144 0.9144)
			(stroke
				(width 0.15)
				(type solid)
			)
			(fill no)
			(layer "F.SilkS")
		)
		(fp_line
			(start 1.25 0.8)
			(end 1.25 -0.8)
			(stroke
				(width 0.05)
				(type solid)
			)
			(layer "F.CrtYd")
		)
		(fp_line
			(start 1.25 -0.8)
			(end -1.25 -0.8)
			(stroke
				(width 0.05)
				(type solid)
			)
			(layer "F.CrtYd")
		)
		(fp_line
			(start -1.25 0.8)
			(end 1.25 0.8)
			(stroke
				(width 0.05)
				(type solid)
			)
			(layer "F.CrtYd")
		)
		(fp_line
			(start -1.25 -0.8)
			(end -1.25 0.8)
			(stroke
				(width 0.05)
				(type solid)
			)
			(layer "F.CrtYd")
		)
		(fp_line
			(start 1 0.5)
			(end -1 0.5)
			(stroke
				(width 0.15)
				(type solid)
			)
			(layer "F.Fab")
		)
		(fp_line
			(start 1 -0.5)
			(end 1 0.5)
			(stroke
				(width 0.15)
				(type solid)
			)
			(layer "F.Fab")
		)
		(fp_line
			(start -1 0.5)
			(end -1 -0.5)
			(stroke
				(width 0.15)
				(type solid)
			)
			(layer "F.Fab")
		)
		(fp_line
			(start -1 0)
			(end -0.508 0.5)
			(stroke
				(width 0.15)
				(type solid)
			)
			(layer "F.Fab")
		)
		(fp_line
			(start -1 -0.5)
			(end 1 -0.5)
			(stroke
				(width 0.15)
				(type solid)
			)
			(layer "F.Fab")
		)
		(fp_circle
			(center -0.9652 0.9144)
			(end -0.9144 0.9144)
			(stroke
				(width 0.15)
				(type solid)
			)
			(fill no)
			(layer "F.Fab")
		)
		(fp_text user "Author: Antmicro"
			(at -1.25 6.0194 0)
			(layer "F.Fab")
			(effects
				(font
					(size 0.7 0.7)
					(thickness 0.15)
				)
				(justify right top)
			)
		)
		(fp_text user "${REFERENCE}"
			(at -1.25 4.8194 0)
			(layer "F.Fab")
			(effects
				(font
					(size 0.7 0.7)
					(thickness 0.15)
				)
				(justify right top)
			)
		)
		(fp_text user "License: Apache-2.0"
			(at -1.25 7.2194 0)
			(layer "F.Fab")
			(effects
				(font
					(size 0.7 0.7)
					(thickness 0.15)
				)
				(justify right top)
			)
		)
		(pad "1" smd roundrect
			(at -0.8875 0.45 180)
			(size 0.525 0.5)
			(layers "F.Cu" "F.Mask" "F.Paste")
			(roundrect_rratio 0.25)
			(net 60 "/FPGA GPIO/HDMI_FPGA.TX2_N")
			(pinfunction "R1.1")
			(pintype "passive")
		)
		(pad "2" smd roundrect
			(at -0.25 0.46 180)
			(size 0.25 0.48)
			(layers "F.Cu" "F.Mask" "F.Paste")
			(roundrect_rratio 0.25)
			(net 82 "/FPGA GPIO/HDMI_FPGA.TX2_P")
			(pinfunction "R2.1")
			(pintype "passive")
		)
		(pad "3" smd roundrect
			(at 0.25 0.46 180)
			(size 0.25 0.48)
			(layers "F.Cu" "F.Mask" "F.Paste")
			(roundrect_rratio 0.25)
			(net 83 "/FPGA GPIO/HDMI_FPGA.TX1_N")
			(pinfunction "R3.1")
			(pintype "passive")
		)
		(pad "4" smd roundrect
			(at 0.8875 0.45 180)
			(size 0.525 0.5)
			(layers "F.Cu" "F.Mask" "F.Paste")
			(roundrect_rratio 0.25)
			(net 84 "/FPGA GPIO/HDMI_FPGA.TX1_P")
			(pinfunction "R4.1")
			(pintype "passive")
		)
		(pad "5" smd roundrect
			(at 0.8875 -0.45 180)
			(size 0.525 0.5)
			(layers "F.Cu" "F.Mask" "F.Paste")
			(roundrect_rratio 0.25)
			(net 546 "/HDMI/PI3HDX_C_TX1_P")
			(pinfunction "R4.2")
			(pintype "passive")
		)
		(pad "6" smd roundrect
			(at 0.25 -0.46 180)
			(size 0.25 0.48)
			(layers "F.Cu" "F.Mask" "F.Paste")
			(roundrect_rratio 0.25)
			(net 550 "/HDMI/PI3HDX_C_TX1_N")
			(pinfunction "R3.2")
			(pintype "passive")
		)
		(pad "7" smd roundrect
			(at -0.25 -0.46 180)
			(size 0.25 0.48)
			(layers "F.Cu" "F.Mask" "F.Paste")
			(roundrect_rratio 0.25)
			(net 57 "/HDMI/PI3HDX_C_TX2_P")
			(pinfunction "R2.2")
			(pintype "passive")
		)
		(pad "8" smd roundrect
			(at -0.8875 -0.45 180)
			(size 0.525 0.5)
			(layers "F.Cu" "F.Mask" "F.Paste")
			(roundrect_rratio 0.25)
			(net 549 "/HDMI/PI3HDX_C_TX2_N")
			(pinfunction "R1.2")
			(pintype "passive")
		)
	)
	(footprint "antmicro-footprints:C_0402_1005Metric"
		(layer "F.Cu")
		(at 175.475 140.9675 90)
		(descr "Capacitor SMD 0402")
		(tags "capacitor SMD 0402")
		(property "Reference" "C99"
			(at 0.9675 0.445 90)
			(layer "F.SilkS")
			(effects
				(font
					(size 0.7 0.7)
					(thickness 0.15)
				)
				(justify left bottom)
			)
		)
		(property "Value" "C_22u_0402"
			(at -1.022927 2.155213 90)
			(layer "F.Fab")
			(hide yes)
			(effects
				(font
					(size 0.7 0.7)
					(thickness 0.15)
				)
				(justify left bottom)
			)
		)
		(property "Datasheet" "https://www.murata.com/products/productdetail?partno=GRM158R60J226ME01%23"
			(at 0 0 90)
			(layer "F.Fab")
			(hide yes)
			(effects
				(font
					(size 1.27 1.27)
					(thickness 0.15)
				)
			)
		)
		(property "Description" "SMD Multilayer Ceramic Capacitor, 22 uF, 4 V, 0402 [1005 Metric], X6S"
			(at 0 0 90)
			(layer "F.Fab")
			(hide yes)
			(effects
				(font
					(size 1.27 1.27)
					(thickness 0.15)
				)
			)
		)
		(property "Author" "Antmicro"
			(at 316.4425 -34.5075 0)
			(layer "F.Fab")
			(hide yes)
			(effects
				(font
					(size 1 1)
					(thickness 0.15)
				)
			)
		)
		(property "Dielectric" ""
			(at 316.4425 -34.5075 0)
			(layer "F.Fab")
			(hide yes)
			(effects
				(font
					(size 1 1)
					(thickness 0.15)
				)
			)
		)
		(property "License" "Apache-2.0"
			(at 316.4425 -34.5075 0)
			(layer "F.Fab")
			(hide yes)
			(effects
				(font
					(size 1 1)
					(thickness 0.15)
				)
			)
		)
		(property "MPN" "GRM158R60J226ME01D"
			(at 316.4425 -34.5075 0)
			(layer "F.Fab")
			(hide yes)
			(effects
				(font
					(size 1 1)
					(thickness 0.15)
				)
			)
		)
		(property "Manufacturer" "Murata"
			(at 316.4425 -34.5075 0)
			(layer "F.Fab")
			(hide yes)
			(effects
				(font
					(size 1 1)
					(thickness 0.15)
				)
			)
		)
		(property "Public" ""
			(at 316.4425 -34.5075 0)
			(layer "F.Fab")
			(hide yes)
			(effects
				(font
					(size 1 1)
					(thickness 0.15)
				)
			)
		)
		(property "Val" "22u"
			(at 316.4425 -34.5075 0)
			(layer "F.Fab")
			(hide yes)
			(effects
				(font
					(size 1 1)
					(thickness 0.15)
				)
			)
		)
		(property "Voltage" ""
			(at 316.4425 -34.5075 0)
			(layer "F.Fab")
			(hide yes)
			(effects
				(font
					(size 1 1)
					(thickness 0.15)
				)
			)
		)
		(sheetname "/Supply/")
		(sheetfile "supply.kicad_sch")
		(attr smd)
		(fp_rect
			(start -0.925 -0.47)
			(end 0.925 0.47)
			(stroke
				(width 0.05)
				(type default)
			)
			(fill no)
			(layer "F.CrtYd")
		)
		(fp_line
			(start 0.504 -0.25)
			(end 0.504 0.248)
			(stroke
				(width 0.15)
				(type solid)
			)
			(layer "F.Fab")
		)
		(fp_line
			(start -0.494 -0.25)
			(end 0.504 -0.25)
			(stroke
				(width 0.15)
				(type solid)
			)
			(layer "F.Fab")
		)
		(fp_line
			(start 0.504 0.248)
			(end -0.494 0.248)
			(stroke
				(width 0.15)
				(type solid)
			)
			(layer "F.Fab")
		)
		(fp_line
			(start -0.494 0.248)
			(end -0.494 -0.25)
			(stroke
				(width 0.15)
				(type solid)
			)
			(layer "F.Fab")
		)
		(fp_text user "Author: Antmicro"
			(at -0.939 3.399 90)
			(layer "F.Fab")
			(effects
				(font
					(size 0.7 0.7)
					(thickness 0.15)
				)
				(justify left bottom)
			)
		)
		(fp_text user "${REFERENCE}"
			(at -0.939 4.599 90)
			(layer "F.Fab")
			(effects
				(font
					(size 0.7 0.7)
					(thickness 0.15)
				)
				(justify left bottom)
			)
		)
		(fp_text user "License: Apache-2.0"
			(at -0.939 5.799 90)
			(layer "F.Fab")
			(effects
				(font
					(size 0.7 0.7)
					(thickness 0.15)
				)
				(justify left bottom)
			)
		)
		(pad "1" smd roundrect
			(at -0.48 0 90)
			(size 0.59 0.64)
			(layers "F.Cu" "F.Mask" "F.Paste")
			(roundrect_rratio 0.25)
			(net 417 "GND")
			(pintype "passive")
		)
		(pad "2" smd roundrect
			(at 0.48 0 90)
			(size 0.59 0.64)
			(layers "F.Cu" "F.Mask" "F.Paste")
			(roundrect_rratio 0.25)
			(net 209 "/Supply/SENSE1_P")
			(pintype "passive")
		)
	)
)
